(kicad_pcb
	(version 20260206)
	(generator "pcbnew")
	(generator_version "10.0")
	(general
		(thickness 1.6)
		(legacy_teardrops no)
	)
	(paper "A4")
	(title_block
		(title "panther-plus-userver — 13130-1b_20150205.brd")
		(comment 1 "Honey Badger (Wiwynn) / footprint 406 of 1509 (DIMM2), pads 149-155 of 210")
	)
	(layers
		(0 "F.Cu" signal "TOP")
		(4 "In1.Cu" signal "L2")
		(6 "In2.Cu" signal "L3")
		(8 "In3.Cu" signal "L4")
		(10 "In4.Cu" signal "L5")
		(12 "In5.Cu" signal "L6")
		(14 "In6.Cu" signal "L7")
		(16 "In7.Cu" signal "L8")
		(18 "In8.Cu" signal "L9")
		(20 "In9.Cu" signal "L10")
		(22 "In10.Cu" signal "L11")
		(2 "B.Cu" signal "BOTTOM")
		(9 "F.Adhes" user "F.Adhesive")
		(11 "B.Adhes" user "B.Adhesive")
		(13 "F.Paste" user "Package Geometry/Pastemask Top")
		(15 "B.Paste" user "Package Geometry/Pastemask Bottom")
		(5 "F.SilkS" user "Ref Des/Silkscreen Top")
		(7 "B.SilkS" user "Ref Des/Silkscreen Bottom")
		(1 "F.Mask" user "Board Geometry/Soldermask Top")
		(3 "B.Mask" user "Board Geometry/Soldermask Bottom")
		(17 "Dwgs.User" user "User.Drawings")
		(19 "Cmts.User" user "User.Comments")
		(21 "Eco1.User" user "User.Eco1")
		(23 "Eco2.User" user "User.Eco2")
		(25 "Edge.Cuts" user "Board Geometry/Outline")
		(27 "Margin" user)
		(31 "F.CrtYd" user "Package Geometry/Place Bound Top")
		(29 "B.CrtYd" user "Package Geometry/Place Bound Bottom")
		(35 "F.Fab" user "Ref Des/Assembly Top")
		(33 "B.Fab" user "Ref Des/Assembly Bottom")
	)
	(footprint ""
		(layer "F.Cu")
		(at 158.500064 -66.699892 180)
		(property "Reference" "DIMM2"
			(at 0 0 180)
			(layer "F.SilkS")
			(hide yes)
			(effects
				(font
					(size 1.27 1.27)
				)
			)
		)
		(property "Value" "DDR3-204P-174-COLAY-1-GP"
			(at -40.682164 -17.468088 180)
			(unlocked yes)
			(layer "F.Fab")
			(hide yes)
			(effects
				(font
					(size 1.016 1.016)
					(thickness 0.1524)
				)
			)
		)
		(property "Device Type" "AS0A626-H8SN-7H-COLAY-1"
			(at -40.682164 -18.992088 180)
			(unlocked yes)
			(layer "F.Fab")
			(hide yes)
			(effects
				(font
					(size 1.016 1.016)
					(thickness 0.1524)
				)
			)
		)
		(duplicate_pad_numbers_are_jumpers no)
		(pad "147" smd custom
			(at 14.549882 4.106672 180)
			(size 0.1143 0.1143)
			(layers "F.Cu" "F.Mask" "F.Paste")
			(net "M_A_DQ39")
			(options
				(clearance outline)
				(anchor circle)
			)
			(primitives
				(gr_poly
					(pts
						(xy 0 0.9017) (xy -0.03175 0.89916) (xy -0.0635 0.889) (xy -0.09144 0.87376) (xy -0.11684 0.85344)
						(xy -0.13716 0.82804) (xy -0.1524 0.8001) (xy -0.16256 0.76835) (xy -0.1651 0.7366) (xy -0.1651 0.11938)
						(xy -0.17272 0.11176) (xy -0.19812 0.0762) (xy -0.2032 0.06604) (xy -0.20701 0.05715) (xy -0.21209 0.04699)
						(xy -0.2159 0.03683) (xy -0.21844 0.02667) (xy -0.22225 0.01524) (xy -0.22352 0.00508) (xy -0.22606 -0.00508)
						(xy -0.22733 -0.01651) (xy -0.22733 -0.02667) (xy -0.2286 -0.0381) (xy -0.22733 -0.04953) (xy -0.22733 -0.05969)
						(xy -0.22606 -0.07112) (xy -0.22352 -0.08128) (xy -0.22225 -0.09144) (xy -0.21844 -0.10287) (xy -0.2159 -0.11303)
						(xy -0.21209 -0.12319) (xy -0.20701 -0.13335) (xy -0.2032 -0.14224) (xy -0.19812 -0.1524) (xy -0.17272 -0.18796)
						(xy -0.1651 -0.19558) (xy -0.1651 -0.7366) (xy -0.16256 -0.76835) (xy -0.1524 -0.8001) (xy -0.13716 -0.82804)
						(xy -0.11684 -0.85344) (xy -0.09144 -0.87376) (xy -0.0635 -0.889) (xy -0.03175 -0.89916) (xy 0 -0.9017)
						(xy 0.03175 -0.89916) (xy 0.0635 -0.889) (xy 0.09144 -0.87376) (xy 0.11684 -0.85344) (xy 0.13716 -0.82804)
						(xy 0.1524 -0.8001) (xy 0.16256 -0.76835) (xy 0.1651 -0.7366) (xy 0.1651 -0.19685) (xy 0.17272 -0.18923)
						(xy 0.17907 -0.18034) (xy 0.18669 -0.17145) (xy 0.19177 -0.16256) (xy 0.19812 -0.15367) (xy 0.20828 -0.13335)
						(xy 0.21971 -0.10287) (xy 0.22225 -0.09271) (xy 0.22479 -0.08128) (xy 0.22606 -0.07112) (xy 0.2286 -0.05969)
						(xy 0.2286 -0.01651) (xy 0.22606 -0.00508) (xy 0.22479 0.00508) (xy 0.22225 0.01651) (xy 0.21971 0.02667)
						(xy 0.20828 0.05715) (xy 0.19812 0.07747) (xy 0.19177 0.08636) (xy 0.18669 0.09525) (xy 0.17907 0.10414)
						(xy 0.17272 0.11303) (xy 0.1651 0.12065) (xy 0.1651 0.7366) (xy 0.16256 0.76835) (xy 0.1524 0.8001)
						(xy 0.13716 0.82804) (xy 0.11684 0.85344) (xy 0.09144 0.87376) (xy 0.0635 0.889) (xy 0.03175 0.89916)
					)
					(width 0)
					(fill yes)
				)
			)
		)
		(pad "148" smd custom
			(at 14.85011 -4.106672 180)
			(size 0.1143 0.1143)
			(layers "F.Cu" "F.Mask" "F.Paste")
			(net "M_A_DQ40")
			(options
				(clearance outline)
				(anchor circle)
			)
			(primitives
				(gr_poly
					(pts
						(xy 0 0.9017) (xy -0.03175 0.89916) (xy -0.0635 0.889) (xy -0.09144 0.87376) (xy -0.11684 0.85344)
						(xy -0.13716 0.82804) (xy -0.1524 0.8001) (xy -0.16256 0.76835) (xy -0.1651 0.7366) (xy -0.1651 0.19685)
						(xy -0.17272 0.18923) (xy -0.17907 0.18034) (xy -0.18669 0.17145) (xy -0.19177 0.16256) (xy -0.19812 0.15367)
						(xy -0.20828 0.13335) (xy -0.21971 0.10287) (xy -0.22225 0.09271) (xy -0.22479 0.08128) (xy -0.22606 0.07112)
						(xy -0.2286 0.05969) (xy -0.2286 0.01651) (xy -0.22606 0.00508) (xy -0.22479 -0.00508) (xy -0.22225 -0.01651)
						(xy -0.21971 -0.02667) (xy -0.20828 -0.05715) (xy -0.19812 -0.07747) (xy -0.19177 -0.08636) (xy -0.18669 -0.09525)
						(xy -0.17907 -0.10414) (xy -0.17272 -0.11303) (xy -0.1651 -0.12065) (xy -0.1651 -0.7366) (xy -0.16256 -0.76835)
						(xy -0.1524 -0.8001) (xy -0.13716 -0.82804) (xy -0.11684 -0.85344) (xy -0.09144 -0.87376) (xy -0.0635 -0.889)
						(xy -0.03175 -0.89916) (xy 0 -0.9017) (xy 0.03175 -0.89916) (xy 0.0635 -0.889) (xy 0.09144 -0.87376)
						(xy 0.11684 -0.85344) (xy 0.13716 -0.82804) (xy 0.1524 -0.8001) (xy 0.16256 -0.76835) (xy 0.1651 -0.7366)
						(xy 0.1651 -0.11938) (xy 0.17272 -0.11176) (xy 0.19812 -0.0762) (xy 0.2032 -0.06604) (xy 0.20701 -0.05715)
						(xy 0.21209 -0.04699) (xy 0.2159 -0.03683) (xy 0.21844 -0.02667) (xy 0.22225 -0.01524) (xy 0.22352 -0.00508)
						(xy 0.22606 0.00508) (xy 0.22733 0.01651) (xy 0.22733 0.02667) (xy 0.2286 0.0381) (xy 0.22733 0.04953)
						(xy 0.22733 0.05969) (xy 0.22606 0.07112) (xy 0.22352 0.08128) (xy 0.22225 0.09144) (xy 0.21844 0.10287)
						(xy 0.2159 0.11303) (xy 0.21209 0.12319) (xy 0.20701 0.13335) (xy 0.2032 0.14224) (xy 0.19812 0.1524)
						(xy 0.17272 0.18796) (xy 0.1651 0.19558) (xy 0.1651 0.7366) (xy 0.16256 0.76835) (xy 0.1524 0.8001)
						(xy 0.13716 0.82804) (xy 0.11684 0.85344) (xy 0.09144 0.87376) (xy 0.0635 0.889) (xy 0.03175 0.89916)
					)
					(width 0)
					(fill yes)
				)
			)
		)
		(pad "149" smd custom
			(at 15.150084 4.106672 180)
			(size 0.1143 0.1143)
			(layers "F.Cu" "F.Mask" "F.Paste")
			(net "GND")
			(options
				(clearance outline)
				(anchor circle)
			)
			(primitives
				(gr_poly
					(pts
						(xy 0 0.9017) (xy -0.03175 0.89916) (xy -0.0635 0.889) (xy -0.09144 0.87376) (xy -0.11684 0.85344)
						(xy -0.13716 0.82804) (xy -0.1524 0.8001) (xy -0.16256 0.76835) (xy -0.1651 0.7366) (xy -0.1651 -0.13462)
						(xy -0.17272 -0.14224) (xy -0.19812 -0.1778) (xy -0.2032 -0.18796) (xy -0.20701 -0.19685) (xy -0.21209 -0.20701)
						(xy -0.2159 -0.21717) (xy -0.21844 -0.22733) (xy -0.22225 -0.23876) (xy -0.22352 -0.24892) (xy -0.22606 -0.25908)
						(xy -0.22733 -0.27051) (xy -0.22733 -0.28067) (xy -0.2286 -0.2921) (xy -0.22733 -0.30353) (xy -0.22733 -0.31369)
						(xy -0.22606 -0.32512) (xy -0.22352 -0.33528) (xy -0.22225 -0.34544) (xy -0.21844 -0.35687) (xy -0.2159 -0.36703)
						(xy -0.21209 -0.37719) (xy -0.20701 -0.38735) (xy -0.2032 -0.39624) (xy -0.19812 -0.4064) (xy -0.17272 -0.44196)
						(xy -0.1651 -0.44958) (xy -0.1651 -0.7366) (xy -0.16256 -0.76835) (xy -0.1524 -0.8001) (xy -0.13716 -0.82804)
						(xy -0.11684 -0.85344) (xy -0.09144 -0.87376) (xy -0.0635 -0.889) (xy -0.03175 -0.89916) (xy 0 -0.9017)
						(xy 0.03175 -0.89916) (xy 0.0635 -0.889) (xy 0.09144 -0.87376) (xy 0.11684 -0.85344) (xy 0.13716 -0.82804)
						(xy 0.1524 -0.8001) (xy 0.16256 -0.76835) (xy 0.1651 -0.7366) (xy 0.1651 -0.44958) (xy 0.17272 -0.44196)
						(xy 0.19812 -0.4064) (xy 0.2032 -0.39624) (xy 0.20701 -0.38735) (xy 0.21209 -0.37719) (xy 0.2159 -0.36703)
						(xy 0.21844 -0.35687) (xy 0.22225 -0.34544) (xy 0.22352 -0.33528) (xy 0.22606 -0.32512) (xy 0.22733 -0.31369)
						(xy 0.22733 -0.30353) (xy 0.2286 -0.2921) (xy 0.22733 -0.28067) (xy 0.22733 -0.27051) (xy 0.22606 -0.25908)
						(xy 0.22352 -0.24892) (xy 0.22225 -0.23876) (xy 0.21844 -0.22733) (xy 0.2159 -0.21717) (xy 0.21209 -0.20701)
						(xy 0.20701 -0.19685) (xy 0.2032 -0.18796) (xy 0.19812 -0.1778) (xy 0.17272 -0.14224) (xy 0.1651 -0.13462)
						(xy 0.1651 0.7366) (xy 0.16256 0.76835) (xy 0.1524 0.8001) (xy 0.13716 0.82804) (xy 0.11684 0.85344)
						(xy 0.09144 0.87376) (xy 0.0635 0.889) (xy 0.03175 0.89916)
					)
					(width 0)
					(fill yes)
				)
			)
		)
		(pad "150" smd custom
			(at 15.450058 -4.106672 180)
			(size 0.1143 0.1143)
			(layers "F.Cu" "F.Mask" "F.Paste")
			(net "M_A_DQ41")
			(options
				(clearance outline)
				(anchor circle)
			)
			(primitives
				(gr_poly
					(pts
						(xy 0 0.9017) (xy -0.03175 0.89916) (xy -0.0635 0.889) (xy -0.09144 0.87376) (xy -0.11684 0.85344)
						(xy -0.13716 0.82804) (xy -0.1524 0.8001) (xy -0.16256 0.76835) (xy -0.1651 0.7366) (xy -0.1651 0.44958)
						(xy -0.17272 0.44196) (xy -0.19812 0.4064) (xy -0.2032 0.39624) (xy -0.20701 0.38735) (xy -0.21209 0.37719)
						(xy -0.2159 0.36703) (xy -0.21844 0.35687) (xy -0.22225 0.34544) (xy -0.22352 0.33528) (xy -0.22606 0.32512)
						(xy -0.22733 0.31369) (xy -0.22733 0.30353) (xy -0.2286 0.2921) (xy -0.22733 0.28067) (xy -0.22733 0.27051)
						(xy -0.22606 0.25908) (xy -0.22352 0.24892) (xy -0.22225 0.23876) (xy -0.21844 0.22733) (xy -0.2159 0.21717)
						(xy -0.21209 0.20701) (xy -0.20701 0.19685) (xy -0.2032 0.18796) (xy -0.19812 0.1778) (xy -0.17272 0.14224)
						(xy -0.1651 0.13462) (xy -0.1651 -0.7366) (xy -0.16256 -0.76835) (xy -0.1524 -0.8001) (xy -0.13716 -0.82804)
						(xy -0.11684 -0.85344) (xy -0.09144 -0.87376) (xy -0.0635 -0.889) (xy -0.03175 -0.89916) (xy 0 -0.9017)
						(xy 0.03175 -0.89916) (xy 0.0635 -0.889) (xy 0.09144 -0.87376) (xy 0.11684 -0.85344) (xy 0.13716 -0.82804)
						(xy 0.1524 -0.8001) (xy 0.16256 -0.76835) (xy 0.1651 -0.7366) (xy 0.1651 0.13462) (xy 0.17272 0.14224)
						(xy 0.19812 0.1778) (xy 0.2032 0.18796) (xy 0.20701 0.19685) (xy 0.21209 0.20701) (xy 0.2159 0.21717)
						(xy 0.21844 0.22733) (xy 0.22225 0.23876) (xy 0.22352 0.24892) (xy 0.22606 0.25908) (xy 0.22733 0.27051)
						(xy 0.22733 0.28067) (xy 0.2286 0.2921) (xy 0.22733 0.30353) (xy 0.22733 0.31369) (xy 0.22606 0.32512)
						(xy 0.22352 0.33528) (xy 0.22225 0.34544) (xy 0.21844 0.35687) (xy 0.2159 0.36703) (xy 0.21209 0.37719)
						(xy 0.20701 0.38735) (xy 0.2032 0.39624) (xy 0.19812 0.4064) (xy 0.17272 0.44196) (xy 0.1651 0.44958)
						(xy 0.1651 0.7366) (xy 0.16256 0.76835) (xy 0.1524 0.8001) (xy 0.13716 0.82804) (xy 0.11684 0.85344)
						(xy 0.09144 0.87376) (xy 0.0635 0.889) (xy 0.03175 0.89916)
					)
					(width 0)
					(fill yes)
				)
			)
		)
		(pad "151" smd custom
			(at 15.750032 4.106672 180)
			(size 0.1143 0.1143)
			(layers "F.Cu" "F.Mask" "F.Paste")
			(net "M_A_DQ44")
			(options
				(clearance outline)
				(anchor circle)
			)
			(primitives
				(gr_poly
					(pts
						(xy 0 0.9017) (xy -0.03175 0.89916) (xy -0.0635 0.889) (xy -0.09144 0.87376) (xy -0.11684 0.85344)
						(xy -0.13716 0.82804) (xy -0.1524 0.8001) (xy -0.16256 0.76835) (xy -0.1651 0.7366) (xy -0.1651 0.11938)
						(xy -0.17272 0.11176) (xy -0.19812 0.0762) (xy -0.2032 0.06604) (xy -0.20701 0.05715) (xy -0.21209 0.04699)
						(xy -0.2159 0.03683) (xy -0.21844 0.02667) (xy -0.22225 0.01524) (xy -0.22352 0.00508) (xy -0.22606 -0.00508)
						(xy -0.22733 -0.01651) (xy -0.22733 -0.02667) (xy -0.2286 -0.0381) (xy -0.22733 -0.04953) (xy -0.22733 -0.05969)
						(xy -0.22606 -0.07112) (xy -0.22352 -0.08128) (xy -0.22225 -0.09144) (xy -0.21844 -0.10287) (xy -0.2159 -0.11303)
						(xy -0.21209 -0.12319) (xy -0.20701 -0.13335) (xy -0.2032 -0.14224) (xy -0.19812 -0.1524) (xy -0.17272 -0.18796)
						(xy -0.1651 -0.19558) (xy -0.1651 -0.7366) (xy -0.16256 -0.76835) (xy -0.1524 -0.8001) (xy -0.13716 -0.82804)
						(xy -0.11684 -0.85344) (xy -0.09144 -0.87376) (xy -0.0635 -0.889) (xy -0.03175 -0.89916) (xy 0 -0.9017)
						(xy 0.03175 -0.89916) (xy 0.0635 -0.889) (xy 0.09144 -0.87376) (xy 0.11684 -0.85344) (xy 0.13716 -0.82804)
						(xy 0.1524 -0.8001) (xy 0.16256 -0.76835) (xy 0.1651 -0.7366) (xy 0.1651 -0.19685) (xy 0.17272 -0.18923)
						(xy 0.17907 -0.18034) (xy 0.18669 -0.17145) (xy 0.19177 -0.16256) (xy 0.19812 -0.15367) (xy 0.20828 -0.13335)
						(xy 0.21971 -0.10287) (xy 0.22225 -0.09271) (xy 0.22479 -0.08128) (xy 0.22606 -0.07112) (xy 0.2286 -0.05969)
						(xy 0.2286 -0.01651) (xy 0.22606 -0.00508) (xy 0.22479 0.00508) (xy 0.22225 0.01651) (xy 0.21971 0.02667)
						(xy 0.20828 0.05715) (xy 0.19812 0.07747) (xy 0.19177 0.08636) (xy 0.18669 0.09525) (xy 0.17907 0.10414)
						(xy 0.17272 0.11303) (xy 0.1651 0.12065) (xy 0.1651 0.7366) (xy 0.16256 0.76835) (xy 0.1524 0.8001)
						(xy 0.13716 0.82804) (xy 0.11684 0.85344) (xy 0.09144 0.87376) (xy 0.0635 0.889) (xy 0.03175 0.89916)
					)
					(width 0)
					(fill yes)
				)
			)
		)
		(pad "152" smd custom
			(at 16.050006 -4.106672 180)
			(size 0.1143 0.1143)
			(layers "F.Cu" "F.Mask" "F.Paste")
			(net "GND")
			(options
				(clearance outline)
				(anchor circle)
			)
			(primitives
				(gr_poly
					(pts
						(xy 0 0.9017) (xy -0.03175 0.89916) (xy -0.0635 0.889) (xy -0.09144 0.87376) (xy -0.11684 0.85344)
						(xy -0.13716 0.82804) (xy -0.1524 0.8001) (xy -0.16256 0.76835) (xy -0.1651 0.7366) (xy -0.1651 0.19685)
						(xy -0.17272 0.18923) (xy -0.17907 0.18034) (xy -0.18669 0.17145) (xy -0.19177 0.16256) (xy -0.19812 0.15367)
						(xy -0.20828 0.13335) (xy -0.21971 0.10287) (xy -0.22225 0.09271) (xy -0.22479 0.08128) (xy -0.22606 0.07112)
						(xy -0.2286 0.05969) (xy -0.2286 0.01651) (xy -0.22606 0.00508) (xy -0.22479 -0.00508) (xy -0.22225 -0.01651)
						(xy -0.21971 -0.02667) (xy -0.20828 -0.05715) (xy -0.19812 -0.07747) (xy -0.19177 -0.08636) (xy -0.18669 -0.09525)
						(xy -0.17907 -0.10414) (xy -0.17272 -0.11303) (xy -0.1651 -0.12065) (xy -0.1651 -0.7366) (xy -0.16256 -0.76835)
						(xy -0.1524 -0.8001) (xy -0.13716 -0.82804) (xy -0.11684 -0.85344) (xy -0.09144 -0.87376) (xy -0.0635 -0.889)
						(xy -0.03175 -0.89916) (xy 0 -0.9017) (xy 0.03175 -0.89916) (xy 0.0635 -0.889) (xy 0.09144 -0.87376)
						(xy 0.11684 -0.85344) (xy 0.13716 -0.82804) (xy 0.1524 -0.8001) (xy 0.16256 -0.76835) (xy 0.1651 -0.7366)
						(xy 0.1651 -0.11938) (xy 0.17272 -0.11176) (xy 0.19812 -0.0762) (xy 0.2032 -0.06604) (xy 0.20701 -0.05715)
						(xy 0.21209 -0.04699) (xy 0.2159 -0.03683) (xy 0.21844 -0.02667) (xy 0.22225 -0.01524) (xy 0.22352 -0.00508)
						(xy 0.22606 0.00508) (xy 0.22733 0.01651) (xy 0.22733 0.02667) (xy 0.2286 0.0381) (xy 0.22733 0.04953)
						(xy 0.22733 0.05969) (xy 0.22606 0.07112) (xy 0.22352 0.08128) (xy 0.22225 0.09144) (xy 0.21844 0.10287)
						(xy 0.2159 0.11303) (xy 0.21209 0.12319) (xy 0.20701 0.13335) (xy 0.2032 0.14224) (xy 0.19812 0.1524)
						(xy 0.17272 0.18796) (xy 0.1651 0.19558) (xy 0.1651 0.7366) (xy 0.16256 0.76835) (xy 0.1524 0.8001)
						(xy 0.13716 0.82804) (xy 0.11684 0.85344) (xy 0.09144 0.87376) (xy 0.0635 0.889) (xy 0.03175 0.89916)
					)
					(width 0)
					(fill yes)
				)
			)
		)
		(pad "153" smd custom
			(at 16.34998 4.106672 180)
			(size 0.1143 0.1143)
			(layers "F.Cu" "F.Mask" "F.Paste")
			(net "M_A_DQ45")
			(options
				(clearance outline)
				(anchor circle)
			)
			(primitives
				(gr_poly
					(pts
						(xy 0 0.9017) (xy -0.03175 0.89916) (xy -0.0635 0.889) (xy -0.09144 0.87376) (xy -0.11684 0.85344)
						(xy -0.13716 0.82804) (xy -0.1524 0.8001) (xy -0.16256 0.76835) (xy -0.1651 0.7366) (xy -0.1651 -0.13462)
						(xy -0.17272 -0.14224) (xy -0.19812 -0.1778) (xy -0.2032 -0.18796) (xy -0.20701 -0.19685) (xy -0.21209 -0.20701)
						(xy -0.2159 -0.21717) (xy -0.21844 -0.22733) (xy -0.22225 -0.23876) (xy -0.22352 -0.24892) (xy -0.22606 -0.25908)
						(xy -0.22733 -0.27051) (xy -0.22733 -0.28067) (xy -0.2286 -0.2921) (xy -0.22733 -0.30353) (xy -0.22733 -0.31369)
						(xy -0.22606 -0.32512) (xy -0.22352 -0.33528) (xy -0.22225 -0.34544) (xy -0.21844 -0.35687) (xy -0.2159 -0.36703)
						(xy -0.21209 -0.37719) (xy -0.20701 -0.38735) (xy -0.2032 -0.39624) (xy -0.19812 -0.4064) (xy -0.17272 -0.44196)
						(xy -0.1651 -0.44958) (xy -0.1651 -0.7366) (xy -0.16256 -0.76835) (xy -0.1524 -0.8001) (xy -0.13716 -0.82804)
						(xy -0.11684 -0.85344) (xy -0.09144 -0.87376) (xy -0.0635 -0.889) (xy -0.03175 -0.89916) (xy 0 -0.9017)
						(xy 0.03175 -0.89916) (xy 0.0635 -0.889) (xy 0.09144 -0.87376) (xy 0.11684 -0.85344) (xy 0.13716 -0.82804)
						(xy 0.1524 -0.8001) (xy 0.16256 -0.76835) (xy 0.1651 -0.7366) (xy 0.1651 -0.44958) (xy 0.17272 -0.44196)
						(xy 0.19812 -0.4064) (xy 0.2032 -0.39624) (xy 0.20701 -0.38735) (xy 0.21209 -0.37719) (xy 0.2159 -0.36703)
						(xy 0.21844 -0.35687) (xy 0.22225 -0.34544) (xy 0.22352 -0.33528) (xy 0.22606 -0.32512) (xy 0.22733 -0.31369)
						(xy 0.22733 -0.30353) (xy 0.2286 -0.2921) (xy 0.22733 -0.28067) (xy 0.22733 -0.27051) (xy 0.22606 -0.25908)
						(xy 0.22352 -0.24892) (xy 0.22225 -0.23876) (xy 0.21844 -0.22733) (xy 0.2159 -0.21717) (xy 0.21209 -0.20701)
						(xy 0.20701 -0.19685) (xy 0.2032 -0.18796) (xy 0.19812 -0.1778) (xy 0.17272 -0.14224) (xy 0.1651 -0.13462)
						(xy 0.1651 0.7366) (xy 0.16256 0.76835) (xy 0.1524 0.8001) (xy 0.13716 0.82804) (xy 0.11684 0.85344)
						(xy 0.09144 0.87376) (xy 0.0635 0.889) (xy 0.03175 0.89916)
					)
					(width 0)
					(fill yes)
				)
			)
		)
	)
)
